# BASEBOARD_FAB2 (Tioga Pass) — schematic netlist excerpt (pin names and nets, part order shuffled) for the footprints in the layout excerpt that follows; sources: Cadence DE-HDL packaged netlist, KiCad conversion of Wiwynn_Tioga_Pass_MB.brd

J8B1  SCONN24_H46321001  SCONN  pkg SM  page 91
  IO1  = GND
  IO2  = SMB_HFI0_CPU0_LVC2_SCL
  IO3  = FM_MODPRST_HFI0_CPU0_LVT2_N
  IO4  = SMB_HFI0_CPU0_LVC2_SDA
  IO5  = LED_HFI0_CPU0_N
  IO6  = RST_HFI0_CPU0_LVT2_N
  IO7  = GND
  IO8  = IRQ_HFI0_CPU0_LVT2_N
  IO9  = GND
  IO10  = SMB_HFI1_CPU0_LVC2_SCL
  IO11  = FM_MODPRST_HFI1_CPU0_LVT2_N
  IO12  = SMB_HFI1_CPU0_LVC2_SDA
  IO13  = LED_HFI1_CPU0_N
  IO14  = RST_HFI1_CPU0_LVT2_N
  IO15  = GND
  IO16  = IRQ_HFI1_CPU0_LVT2_N
  IO17  = TP_HFI_IO_CONN0_RSVD_17
  IO18  = P3V3
  IO19  = PWRGD_PVPP_ABC
  IO20  = P3V3
  IO21  = PVPP_ABC
  IO22  = SMB_OCP_FRU_STBY_LVC3_SCL
  IO23  = GND
  IO24  = SMB_OCP_FRU_STBY_LVC3_SDA
  MP1  = GND
  MP2  = GND

(kicad_pcb
	(version 20260206)
	(generator "pcbnew")
	(generator_version "10.0")
	(general
		(thickness 1.6)
		(legacy_teardrops no)
	)
	(paper "A4")
	(title_block
		(title "Wiwynn_Tioga_Pass_MB.brd")
		(comment 1 "Tioga Pass / footprint 2230 of 4770 (J8B1), pads 1-28 of 28")
	)
	(layers
		(0 "F.Cu" signal "TOP")
		(4 "In1.Cu" signal "L2GND")
		(6 "In2.Cu" signal "L3")
		(8 "In3.Cu" signal "L4GND")
		(10 "In4.Cu" signal "L5")
		(12 "In5.Cu" signal "L6GND")
		(14 "In6.Cu" signal "L7VCC")
		(16 "In7.Cu" signal "L8VCC")
		(18 "In8.Cu" signal "L9GND")
		(20 "In9.Cu" signal "L10")
		(22 "In10.Cu" signal "L11GND")
		(24 "In11.Cu" signal "L12")
		(26 "In12.Cu" signal "L13GND")
		(2 "B.Cu" signal "BOTTOM")
		(9 "F.Adhes" user "F.Adhesive")
		(11 "B.Adhes" user "B.Adhesive")
		(13 "F.Paste" user "Package Geometry/Pastemask Top")
		(15 "B.Paste" user "Package Geometry/Pastemask Bottom")
		(5 "F.SilkS" user "Ref Des/Silkscreen Top")
		(7 "B.SilkS" user "Ref Des/Silkscreen Bottom")
		(1 "F.Mask" user "Board Geometry/Soldermask Top")
		(3 "B.Mask" user "Board Geometry/Soldermask Bottom")
		(17 "Dwgs.User" user "User.Drawings")
		(19 "Cmts.User" user "User.Comments")
		(21 "Eco1.User" user "User.Eco1")
		(23 "Eco2.User" user "User.Eco2")
		(25 "Edge.Cuts" user "Board Geometry/Outline")
		(27 "Margin" user)
		(31 "F.CrtYd" user "Package Geometry/Place Bound Top")
		(29 "B.CrtYd" user "Package Geometry/Place Bound Bottom")
		(35 "F.Fab" user "Ref Des/Assembly Top")
		(33 "B.Fab" user "Ref Des/Assembly Bottom")
	)
	(footprint ""
		(layer "F.Cu")
		(at 415.191194 -132.7404)
		(property "Reference" "J8B1"
			(at 1.59258 -3.68427 0)
			(unlocked yes)
			(layer "F.SilkS")
			(effects
				(font
					(size 0.7874 0.5842)
					(thickness 0.1524)
				)
				(justify left)
			)
		)
		(property "Value" ""
			(at 0 0 0)
			(layer "F.Fab")
			(effects
				(font
					(size 1.27 1.27)
				)
			)
		)
		(duplicate_pad_numbers_are_jumpers no)
		(pad "" np_thru_hole circle
			(at 0.89408 -0.849884)
			(size 0.254 0.254)
			(drill 0.5588)
			(layers "*.Cu" "*.Mask")
			(clearance 0.4699)
			(thermal_gap 0.4699)
		)
		(pad "" np_thru_hole circle
			(at 0.89408 11.850116)
			(size 0.254 0.254)
			(drill 0.5588)
			(layers "*.Cu" "*.Mask")
			(clearance 0.4699)
			(thermal_gap 0.4699)
		)
		(pad "1" smd rect
			(at 0 0)
			(size 1.6002 0.6096)
			(layers "F.Cu" "F.Mask" "F.Paste")
			(net "GND")
		)
		(pad "2" smd rect
			(at 5.588 0)
			(size 1.6002 0.6096)
			(layers "F.Cu" "F.Mask" "F.Paste")
			(net "SMB_HFI0_CPU0_LVC2_SCL")
		)
		(pad "3" smd rect
			(at 0 0.999998)
			(size 1.6002 0.6096)
			(layers "F.Cu" "F.Mask" "F.Paste")
			(net "FM_MODPRST_HFI0_CPU0_LVT2_N")
		)
		(pad "4" smd rect
			(at 5.588 0.999998)
			(size 1.6002 0.6096)
			(layers "F.Cu" "F.Mask" "F.Paste")
			(net "SMB_HFI0_CPU0_LVC2_SDA")
		)
		(pad "5" smd rect
			(at 0 1.999996)
			(size 1.6002 0.6096)
			(layers "F.Cu" "F.Mask" "F.Paste")
			(net "LED_HFI0_CPU0_N")
		)
		(pad "6" smd rect
			(at 5.588 1.999996)
			(size 1.6002 0.6096)
			(layers "F.Cu" "F.Mask" "F.Paste")
			(net "RST_HFI0_CPU0_LVT2_N")
		)
		(pad "7" smd rect
			(at 0 2.999994)
			(size 1.6002 0.6096)
			(layers "F.Cu" "F.Mask" "F.Paste")
			(net "GND")
		)
		(pad "8" smd rect
			(at 5.588 2.999994)
			(size 1.6002 0.6096)
			(layers "F.Cu" "F.Mask" "F.Paste")
			(net "IRQ_HFI0_CPU0_LVT2_N")
		)
		(pad "9" smd rect
			(at 0 3.999992)
			(size 1.6002 0.6096)
			(layers "F.Cu" "F.Mask" "F.Paste")
			(net "GND")
		)
		(pad "10" smd rect
			(at 5.588 3.999992)
			(size 1.6002 0.6096)
			(layers "F.Cu" "F.Mask" "F.Paste")
			(net "SMB_HFI1_CPU0_LVC2_SCL")
		)
		(pad "11" smd rect
			(at 0 4.99999)
			(size 1.6002 0.6096)
			(layers "F.Cu" "F.Mask" "F.Paste")
			(net "FM_MODPRST_HFI1_CPU0_LVT2_N")
		)
		(pad "12" smd rect
			(at 5.588 4.99999)
			(size 1.6002 0.6096)
			(layers "F.Cu" "F.Mask" "F.Paste")
			(net "SMB_HFI1_CPU0_LVC2_SDA")
		)
		(pad "13" smd rect
			(at 0 5.999988)
			(size 1.6002 0.6096)
			(layers "F.Cu" "F.Mask" "F.Paste")
			(net "LED_HFI1_CPU0_N")
		)
		(pad "14" smd rect
			(at 5.588 5.999988)
			(size 1.6002 0.6096)
			(layers "F.Cu" "F.Mask" "F.Paste")
			(net "RST_HFI1_CPU0_LVT2_N")
		)
		(pad "15" smd rect
			(at 0 6.999986)
			(size 1.6002 0.6096)
			(layers "F.Cu" "F.Mask" "F.Paste")
			(net "GND")
		)
		(pad "16" smd rect
			(at 5.588 6.999986)
			(size 1.6002 0.6096)
			(layers "F.Cu" "F.Mask" "F.Paste")
			(net "IRQ_HFI1_CPU0_LVT2_N")
		)
		(pad "17" smd rect
			(at 0 7.999984)
			(size 1.6002 0.6096)
			(layers "F.Cu" "F.Mask" "F.Paste")
			(net "TP_HFI_IO_CONN0_RSVD_17")
		)
		(pad "18" smd rect
			(at 5.588 7.999984)
			(size 1.6002 0.6096)
			(layers "F.Cu" "F.Mask" "F.Paste")
			(net "P3V3")
		)
		(pad "19" smd rect
			(at 0 8.999982)
			(size 1.6002 0.6096)
			(layers "F.Cu" "F.Mask" "F.Paste")
			(net "PWRGD_PVPP_ABC")
		)
		(pad "20" smd rect
			(at 5.588 8.999982)
			(size 1.6002 0.6096)
			(layers "F.Cu" "F.Mask" "F.Paste")
			(net "P3V3")
		)
		(pad "21" smd rect
			(at 0 9.99998)
			(size 1.6002 0.6096)
			(layers "F.Cu" "F.Mask" "F.Paste")
			(net "PVPP_ABC")
		)
		(pad "22" smd rect
			(at 5.588 9.99998)
			(size 1.6002 0.6096)
			(layers "F.Cu" "F.Mask" "F.Paste")
			(net "SMB_OCP_FRU_STBY_LVC3_SCL")
		)
		(pad "23" smd rect
			(at 0 10.999978)
			(size 1.6002 0.6096)
			(layers "F.Cu" "F.Mask" "F.Paste")
			(net "GND")
		)
		(pad "24" smd rect
			(at 5.588 10.999978)
			(size 1.6002 0.6096)
			(layers "F.Cu" "F.Mask" "F.Paste")
			(net "SMB_OCP_FRU_STBY_LVC3_SDA")
		)
		(pad "MP1" smd rect
			(at 3.19405 -1.325118)
			(size 1.8034 0.889)
			(layers "F.Cu" "F.Mask" "F.Paste")
			(net "GND")
		)
		(pad "MP2" smd rect
			(at 3.19405 12.325096)
			(size 1.8034 0.889)
			(layers "F.Cu" "F.Mask" "F.Paste")
			(net "GND")
		)
	)
)
